G04 ================== begin FILE IDENTIFICATION RECORD ==================*
G04 Layout Name:  D:/<user>/Wistron_project/16347-sc/gbr/16347-sc.brd*
G04 Film Name:    L2*
G04 File Format:  Gerber RS274X*
G04 File Origin:  Cadence Allegro 16.5-S056*
G04 Origin Date:  Tue Mar 14 17:08:23 2017*
G04 *
G04 Layer:  VIA CLASS/BOTTOM*
G04 Layer:  PIN/BOTTOM*
G04 Layer:  ETCH/BOTTOM*
G04 Layer:  DRAWING FORMAT/LAYER_PCB_STORY*
G04 Layer:  DRAWING FORMAT/LAYER_L2*
G04 *
G04 Offset:    (0.00 0.00)*
G04 Mirror:    No*
G04 Mode:      Positive*
G04 Rotation:  0*
G04 FullContactRelief:  No*
G04 UndefLineWidth:     6.00*
G04 ================== end FILE IDENTIFICATION RECORD ====================*
%FSLAX35Y35*MOIN*%
%IR0*IPPOS*OFA0.00000B0.00000*MIA0B0*SFA1.00000B1.00000*%
%AMMACRO22*
4,1,40,.013,-.017,
-.013,-.017,
-.013695,-.016939,
-.014368,-.016759,
-.015,-.016464,
-.015571,-.016064,
-.016064,-.015571,
-.016464,-.015,
-.016759,-.014368,
-.016939,-.013695,
-.017,-.013,
-.017,.013,
-.016939,.013695,
-.016759,.014368,
-.016464,.015,
-.016064,.015571,
-.015571,.016064,
-.015,.016464,
-.014368,.016759,
-.013695,.016939,
-.013,.017,
.013,.017,
.013695,.016939,
.014368,.016759,
.015,.016464,
.015571,.016064,
.016064,.015571,
.016464,.015,
.016759,.014368,
.016939,.013695,
.017,.013,
.017,-.013,
.016939,-.013695,
.016759,-.014368,
.016464,-.015,
.016064,-.015571,
.015571,-.016064,
.015,-.016464,
.014368,-.016759,
.013695,-.016939,
.013,-.017,
0.0*
%
%ADD22MACRO22*%
%AMMACRO17*
4,1,40,-.017,-.013,
-.017,.013,
-.016939,.013695,
-.016759,.014368,
-.016464,.015,
-.016064,.015571,
-.015571,.016064,
-.015,.016464,
-.014368,.016759,
-.013695,.016939,
-.013,.017,
.013,.017,
.013695,.016939,
.014368,.016759,
.015,.016464,
.015571,.016064,
.016064,.015571,
.016464,.015,
.016759,.014368,
.016939,.013695,
.017,.013,
.017,-.013,
.016939,-.013695,
.016759,-.014368,
.016464,-.015,
.016064,-.015571,
.015571,-.016064,
.015,-.016464,
.014368,-.016759,
.013695,-.016939,
.013,-.017,
-.013,-.017,
-.013695,-.016939,
-.014368,-.016759,
-.015,-.016464,
-.015571,-.016064,
-.016064,-.015571,
-.016464,-.015,
-.016759,-.014368,
-.016939,-.013695,
-.017,-.013,
0.0*
%
%ADD17MACRO17*%
%ADD10C,.01*%
%ADD13C,.04*%
%ADD12C,.022*%
%ADD18C,.024*%
%AMMACRO16*
4,1,40,.007,-.0225,
.008389,-.022378,
.009736,-.022018,
.011,-.021428,
.012142,-.020628,
.013128,-.019642,
.013928,-.0185,
.014518,-.017236,
.014878,-.015889,
.015,-.0145,
.015,.0145,
.014878,.015889,
.014518,.017236,
.013928,.0185,
.013128,.019642,
.012142,.020628,
.011,.021428,
.009736,.022018,
.008389,.022378,
.007,.0225,
-.007,.0225,
-.008389,.022378,
-.009736,.022018,
-.011,.021428,
-.012142,.020628,
-.013128,.019642,
-.013928,.0185,
-.014518,.017236,
-.014878,.015889,
-.015,.0145,
-.015,-.0145,
-.014878,-.015889,
-.014518,-.017236,
-.013928,-.0185,
-.013128,-.019642,
-.012142,-.020628,
-.011,-.021428,
-.009736,-.022018,
-.008389,-.022378,
-.007,-.0225,
.007,-.0225,
0.0*
%
%ADD16MACRO16*%
%AMMACRO14*
4,1,40,.007,-.011,
-.007,-.011,
-.007695,-.010939,
-.008368,-.010759,
-.009,-.010464,
-.009571,-.010064,
-.010064,-.009571,
-.010464,-.009,
-.010759,-.008368,
-.010939,-.007695,
-.011,-.007,
-.011,.007,
-.010939,.007695,
-.010759,.008368,
-.010464,.009,
-.010064,.009571,
-.009571,.010064,
-.009,.010464,
-.008368,.010759,
-.007695,.010939,
-.007,.011,
.007,.011,
.007695,.010939,
.008368,.010759,
.009,.010464,
.009571,.010064,
.010064,.009571,
.010464,.009,
.010759,.008368,
.010939,.007695,
.011,.007,
.011,-.007,
.010939,-.007695,
.010759,-.008368,
.010464,-.009,
.010064,-.009571,
.009571,-.010064,
.009,-.010464,
.008368,-.010759,
.007695,-.010939,
.007,-.011,
0.0*
%
%ADD14MACRO14*%
%AMMACRO15*
4,1,40,.007,-.011,
-.007,-.011,
-.007695,-.010939,
-.008368,-.010759,
-.009,-.010464,
-.009571,-.010064,
-.010064,-.009571,
-.010464,-.009,
-.010759,-.008368,
-.010939,-.007695,
-.011,-.007,
-.011,.007,
-.010939,.007695,
-.010759,.008368,
-.010464,.009,
-.010064,.009571,
-.009571,.010064,
-.009,.010464,
-.008368,.010759,
-.007695,.010939,
-.007,.011,
.007,.011,
.007695,.010939,
.008368,.010759,
.009,.010464,
.009571,.010064,
.010064,.009571,
.010464,.009,
.010759,.008368,
.010939,.007695,
.011,.007,
.011,-.007,
.010939,-.007695,
.010759,-.008368,
.010464,-.009,
.010064,-.009571,
.009571,-.010064,
.009,-.010464,
.008368,-.010759,
.007695,-.010939,
.007,-.011,
0.0*
%
%ADD15MACRO15*%
%ADD20R,.05X.065*%
%ADD24R,.024X.059*%
%ADD11C,.237*%
%ADD23R,.059X.079*%
%AMMACRO21*
4,1,40,.013,-.017,
-.013,-.017,
-.013695,-.016939,
-.014368,-.016759,
-.015,-.016464,
-.015571,-.016064,
-.016064,-.015571,
-.016464,-.015,
-.016759,-.014368,
-.016939,-.013695,
-.017,-.013,
-.017,.013,
-.016939,.013695,
-.016759,.014368,
-.016464,.015,
-.016064,.015571,
-.015571,.016064,
-.015,.016464,
-.014368,.016759,
-.013695,.016939,
-.013,.017,
.013,.017,
.013695,.016939,
.014368,.016759,
.015,.016464,
.015571,.016064,
.016064,.015571,
.016464,.015,
.016759,.014368,
.016939,.013695,
.017,.013,
.017,-.013,
.016939,-.013695,
.016759,-.014368,
.016464,-.015,
.016064,-.015571,
.015571,-.016064,
.015,-.016464,
.014368,-.016759,
.013695,-.016939,
.013,-.017,
0.0*
%
%ADD21MACRO21*%
%AMMACRO19*
4,1,40,-.017,-.013,
-.017,.013,
-.016939,.013695,
-.016759,.014368,
-.016464,.015,
-.016064,.015571,
-.015571,.016064,
-.015,.016464,
-.014368,.016759,
-.013695,.016939,
-.013,.017,
.013,.017,
.013695,.016939,
.014368,.016759,
.015,.016464,
.015571,.016064,
.016064,.015571,
.016464,.015,
.016759,.014368,
.016939,.013695,
.017,.013,
.017,-.013,
.016939,-.013695,
.016759,-.014368,
.016464,-.015,
.016064,-.015571,
.015571,-.016064,
.015,-.016464,
.014368,-.016759,
.013695,-.016939,
.013,-.017,
-.013,-.017,
-.013695,-.016939,
-.014368,-.016759,
-.015,-.016464,
-.015571,-.016064,
-.016064,-.015571,
-.016464,-.015,
-.016759,-.014368,
-.016939,-.013695,
-.017,-.013,
0.0*
%
%ADD19MACRO19*%
%ADD25C,.02*%
%ADD26C,.03*%
%ADD27C,.015*%
%ADD28C,.005*%
%ADD29C,.006*%
%ADD30C,.09204*%
%ADD31C,.11004*%
%ADD32C,.13904*%
G75*
%LPD*%
G75*
G36*
G01X3937Y-936D02*
G02X3001Y0I0J936D01*
G01Y15670D01*
G02X3783Y15789I400J0D01*
G03Y23579I12457J3895D01*
G02X3001Y23698I-382J119D01*
G01Y35441D01*
G02X3928Y36368I936J-9D01*
G01X33885D01*
G03X40796Y43307I-28J6939D01*
G01Y63779D01*
G02X41733Y64716I937J0D01*
G01X65359D01*
G02X66290Y63785I-8J-939D01*
G01Y43075D01*
G03X73121Y36344I6831J101D01*
G01X156101D01*
G03X163042Y43286I-1J6942D01*
G01Y67717D01*
G02X163977Y68652I935J0D01*
G01X223048D01*
G02X223967Y67733I-22J-941D01*
G01Y43263D01*
G03X230906Y36366I6939J42D01*
G01X280068D01*
X280593Y35841D01*
Y34317D01*
X279992Y33716D01*
X253500D01*
X253498Y33715D01*
X252658D01*
X249485Y30542D01*
X242646D01*
X241240Y29136D01*
Y26398D01*
X238507Y23665D01*
Y20327D01*
X240386Y18448D01*
X247557D01*
X250106Y20997D01*
X253351D01*
X254120Y20228D01*
Y13653D01*
X254119Y13643D01*
G03X254110Y13470I1592J-170D01*
G01Y12070D01*
G03X254120Y11887I1601J-4D01*
G01Y11859D01*
X253922Y11661D01*
X230440D01*
X230397Y11802D01*
G03X227978Y13499I-2297J-702D01*
G01X227890Y13494D01*
X225262Y16122D01*
X223689D01*
X216239Y23572D01*
Y63927D01*
X213812Y66354D01*
X186806D01*
X185100Y64648D01*
Y56100D01*
X184910Y55910D01*
X174586D01*
Y55900D01*
X174400D01*
X172550Y54050D01*
Y47850D01*
X172600Y47800D01*
Y34100D01*
X168300Y29800D01*
X152800D01*
X151500Y28500D01*
Y18000D01*
X149702Y16202D01*
X143198D01*
X142500Y16900D01*
Y20100D01*
X139700Y22900D01*
Y29944D01*
X137572Y32072D01*
X136453D01*
X136415Y32088D01*
G03X134548Y32072I-915J-2112D01*
G01X127101D01*
G03X125111I-995J-2076D01*
G01X113178D01*
G03X110870I-1154J-1992D01*
G01X103963D01*
G03X101209I-1377J-1845D01*
G01X72082D01*
X61554Y42600D01*
Y57354D01*
X60095Y58813D01*
X46830D01*
X45470Y57453D01*
Y52084D01*
X45464Y52061D01*
G03Y50939I2336J-561D01*
G01X45470Y50916D01*
Y50030D01*
X46200Y49300D01*
Y43700D01*
X56400Y33500D01*
Y16700D01*
X57900Y15200D01*
X66700D01*
X67400Y15900D01*
Y19400D01*
X68000Y20000D01*
X72000D01*
X72500Y19500D01*
Y13800D01*
X73200Y13100D01*
X75200D01*
X75600Y12700D01*
Y12165D01*
G03X75598Y12100I1599J-82D01*
G01Y10700D01*
G03X75600Y10635I1601J17D01*
G01Y7588D01*
X76270Y6918D01*
X80802D01*
G03X83198I1198J2082D01*
G01X89799D01*
X94829Y1888D01*
X94879D01*
X94919Y1848D01*
X169789D01*
X185387Y17446D01*
X190973D01*
X206657Y1762D01*
X206885D01*
X208900Y-253D01*
G02X208618Y-936I-282J-283D01*
G01X3937D01*
G37*
G36*
G01X134757Y11843D02*
X133800Y12800D01*
Y20800D01*
X134100Y21100D01*
X139300D01*
X140700Y19700D01*
Y16300D01*
X142000Y15000D01*
X152200D01*
X153600Y16400D01*
Y27800D01*
X153900Y28100D01*
X165800D01*
X166900Y27000D01*
Y15000D01*
X162900Y11000D01*
X137176D01*
G03X134861Y11862I-1876J-1500D01*
G01X134757Y11843D01*
G37*
G36*
G01X94600Y22500D02*
X94900Y22800D01*
X104400D01*
X105000Y22200D01*
Y15700D01*
X104500Y15200D01*
X95400D01*
X94600Y16000D01*
Y22500D01*
G37*
G36*
G01X190190Y55910D02*
X190100Y56000D01*
Y64300D01*
X190900Y65100D01*
X200300D01*
X200900Y64500D01*
Y56100D01*
X200710Y55910D01*
X190190D01*
G37*
G36*
G01X419200Y12700D02*
X414916Y8416D01*
X317387D01*
X316700Y9103D01*
Y17900D01*
X317200Y18400D01*
X320500D01*
X321700Y17200D01*
X412000D01*
X412700Y17900D01*
Y22200D01*
X413200Y22700D01*
X416400D01*
X417100Y22000D01*
Y15800D01*
X417500Y15400D01*
X418900D01*
X419200Y15100D01*
Y14555D01*
G03X419198Y14500I1599J-86D01*
G01Y13100D01*
G03X419200Y13045I1601J31D01*
G01Y12700D01*
G37*
G36*
G01X293242Y45276D02*
X292385Y44419D01*
X289754D01*
X289221Y44952D01*
Y63779D01*
G02X290158Y64716I937J0D01*
G01X313780D01*
G02X314716Y63780I-18J-954D01*
G01Y43287D01*
G03X321654Y36369I6938J20D01*
G01X406498D01*
G03X413434Y43306I-1J6937D01*
G01Y63736D01*
G02X414426Y64716I950J30D01*
G01X437996D01*
G02X438928Y63790I-4J-936D01*
G01Y43242D01*
G03X445866Y36369I6938J65D01*
G01X463915D01*
X464816Y35468D01*
Y30549D01*
X459161Y24894D01*
X450552D01*
X445387Y30059D01*
X441925D01*
X434335Y37649D01*
Y55804D01*
X432631Y57508D01*
X420176D01*
X418000Y55332D01*
Y40000D01*
X406500Y28500D01*
Y27865D01*
G03X406498Y27800I1599J-82D01*
G01Y25498D01*
X405500Y24500D01*
X324732D01*
X310693Y38538D01*
X310690D01*
X309992Y39237D01*
Y55837D01*
X308418Y57411D01*
X294954D01*
X293242Y55699D01*
Y45276D01*
G37*
G36*
G01X501576Y17666D02*
X502452Y18542D01*
X506170D01*
X507696Y17016D01*
X537671D01*
X539042Y18387D01*
Y20994D01*
X539740Y21692D01*
X543110D01*
X544285Y20517D01*
Y16877D01*
X545898Y15264D01*
Y12105D01*
X545896Y12103D01*
Y11619D01*
X539281Y5004D01*
X440876D01*
X440092Y5788D01*
Y16425D01*
X440917Y17250D01*
X461730D01*
X472628Y28148D01*
X474926D01*
X476708Y26366D01*
Y24921D01*
X476691Y24841D01*
X476683Y24823D01*
G03X501566Y17602I11998J-5138D01*
G01X501576Y17666D01*
G37*
G36*
G01X557121Y-936D02*
G02X556839Y-253I0J400D01*
G01X558799Y1708D01*
X648968D01*
X649023Y1762D01*
X654676D01*
X660502Y7588D01*
Y16192D01*
X660860Y16550D01*
X667848D01*
X669297Y17999D01*
Y28156D01*
X683210Y42069D01*
Y55207D01*
X681489Y56928D01*
X667219D01*
X665729Y55438D01*
Y39612D01*
X660314Y34197D01*
X630722D01*
X624744Y28219D01*
Y25071D01*
X623409Y23736D01*
X577476D01*
X571859Y29353D01*
X565542D01*
X558617Y36278D01*
Y55774D01*
X556519Y57872D01*
X543696D01*
X542290Y56466D01*
Y38124D01*
X527668Y23502D01*
X512108D01*
X500969Y34641D01*
Y35961D01*
X501377Y36369D01*
X530744D01*
G03X537647Y43307I-35J6938D01*
G01Y63789D01*
G02X538582Y64716I935J-8D01*
G01X562205D01*
G02X563141Y63783I0J-936D01*
G01Y43149D01*
G03X569989Y36369I6940J162D01*
G01X654921D01*
G03X661859Y43286I0J6938D01*
G01Y63780D01*
G02X662809Y64716I936J0D01*
G01X686415D01*
X686417Y64715D01*
G02X687353Y63777I-10J-946D01*
G01Y42129D01*
G03X693675Y36369I6974J1305D01*
G01X724420D01*
G02X725345Y35434I-10J-935D01*
G01Y23698D01*
G02X724563Y23579I-400J0D01*
G03Y15789I-12457J-3895D01*
G02X725345Y15670I382J-119D01*
G01Y0D01*
G02X724409Y-936I-936J0D01*
G01X557121D01*
G37*
G36*
G01X568628Y6603D02*
X567452Y7779D01*
Y15166D01*
X568711Y16425D01*
X622885D01*
X622898Y16423D01*
G03X623702I402J3177D01*
G01X623715Y16425D01*
X630316D01*
X631544Y17653D01*
Y21074D01*
X631796Y21326D01*
X635782D01*
X636003Y21105D01*
Y15438D01*
X637692Y13749D01*
Y11043D01*
X637255Y10606D01*
X637211Y10591D01*
G03X636104Y9815I770J-2275D01*
G01X634660D01*
X631448Y6603D01*
X568628D01*
G37*
%LPC*%
G75*
G54D30*
X35851Y28624D03*
X693601Y10159D03*
G54D31*
X35185Y15572D03*
X693024Y26550D03*
G54D32*
X47737Y19685D03*
X680610D03*
%LPD*%
G75*
G54D10*
X35185Y15572D03*
X47737Y19685D03*
X16240Y99213D03*
Y233859D03*
Y368505D03*
Y503151D03*
Y637797D03*
Y772443D03*
Y907089D03*
X693024Y26550D03*
X680610Y19685D03*
X784745D03*
Y154331D03*
Y288977D03*
Y423623D03*
Y558269D03*
Y692915D03*
Y827561D03*
G54D11*
X16240Y19684D03*
X301968Y19685D03*
X488681Y19684D03*
X712106D03*
G54D20*
X146000Y19500D03*
X157000D03*
G54D21*
X149700Y26300D03*
G54D12*
X38675Y22425D03*
X20459Y5682D03*
X35539Y4546D03*
X4758Y4649D03*
X41942Y46869D03*
X42071Y58644D03*
X5223Y34706D03*
X30374Y34551D03*
X90368Y245D03*
X63477Y4598D03*
X71000Y11600D03*
X84600Y12000D03*
X59871Y19900D03*
X59100Y56200D03*
X55513Y51513D03*
X47800Y56500D03*
X51573Y51573D03*
X76200Y35200D03*
X65000Y45100D03*
X65100Y59000D03*
X54026Y28870D03*
X46376Y36160D03*
X113912Y245D03*
X124500Y12100D03*
X111100Y10400D03*
X100000Y16500D03*
X135500Y29976D03*
X126106Y29996D03*
X102586Y30227D03*
X112024Y30080D03*
X99000Y35000D03*
X145601Y245D03*
X179537Y9829D03*
X174542Y4205D03*
X140900Y23800D03*
X139300Y19000D03*
X162191Y24351D03*
X165593Y21701D03*
X175800Y67500D03*
X164200Y62000D03*
X164378Y52020D03*
X145200Y26300D03*
X225477Y20626D03*
X189652Y8444D03*
X202034Y4247D03*
X233765Y34883D03*
X219878Y32075D03*
X217446Y46840D03*
Y51035D03*
X222700Y60100D03*
X216500Y67500D03*
X197800D03*
X199700Y63910D03*
X195500D03*
X191500D03*
X249762Y12946D03*
X265042Y13093D03*
X238391Y14434D03*
X241359Y21413D03*
X238755Y26619D03*
X279170Y35245D03*
X256656Y35189D03*
X245853Y31620D03*
X323200Y13800D03*
X283197Y20870D03*
X307599Y54564D03*
X302200Y51718D03*
X296005Y55029D03*
X304088Y48291D03*
X290350Y46275D03*
X290660Y58851D03*
X316800Y35900D03*
X313200Y45500D03*
X313500Y58100D03*
X348900Y13700D03*
X330300Y26000D03*
X365800Y26400D03*
X339400Y34800D03*
X404600Y14400D03*
X383600Y14000D03*
X414700Y13800D03*
X405000Y20700D03*
X420635Y54538D03*
X424211Y52000D03*
X394400Y26300D03*
X402400Y34800D03*
X414600Y44600D03*
X414700Y58000D03*
X384600Y34800D03*
X455689Y15598D03*
X446135Y10537D03*
X428600Y13800D03*
X447000Y20700D03*
X431894Y54627D03*
X428151Y52151D03*
X436012Y59651D03*
X437768Y51052D03*
X438311Y39148D03*
X448019Y35172D03*
X462893D03*
X455817Y26237D03*
X516716Y15930D03*
X501900Y10348D03*
X473919Y10744D03*
X518856Y25583D03*
X503159Y35111D03*
X473300Y25875D03*
X563034Y312D03*
X532070Y10129D03*
X541225Y13900D03*
X554500Y13000D03*
X531500Y20300D03*
X555996Y54409D03*
X552364Y52136D03*
X544789Y54552D03*
X548424Y52000D03*
X565606Y36026D03*
X561619Y47946D03*
X561954Y58858D03*
X538954Y59320D03*
X538911Y42406D03*
X529979Y35111D03*
X601510Y277D03*
X614586Y25544D03*
X580014Y25376D03*
X580128Y14830D03*
X574168Y7737D03*
X573300Y20500D03*
X615510Y35060D03*
X581051Y35186D03*
X646777Y311D03*
X628333Y278D03*
X662275Y4597D03*
X625457Y14410D03*
X617398Y7695D03*
X632900Y13300D03*
X647600Y12500D03*
X623300Y19600D03*
X644052Y35251D03*
X663106Y43749D03*
X663022Y59320D03*
X695912Y18399D03*
X671342Y13872D03*
X704646Y4135D03*
X684016Y4178D03*
X665500Y19700D03*
X680189Y54619D03*
X676576Y52380D03*
X668373Y54326D03*
X672636Y52380D03*
X685686Y59530D03*
X686484Y39279D03*
X701971Y35249D03*
X670753Y27514D03*
X724174Y4463D03*
X723902Y35018D03*
G54D13*
G01X283197Y20870D02*
X287790Y25463D01*
Y26527D01*
X296600Y35337D01*
X309367D01*
X324204Y20500D01*
X395500D01*
G01X405000Y20700D02*
X404800Y20500D01*
X395500D01*
G01X447000Y20700D02*
X459900D01*
X473386Y34186D01*
X496214D01*
X510100Y20300D01*
X523900D01*
G01X531500D02*
X523900D01*
G01X623300Y19600D02*
X622400Y20500D01*
X582700D01*
G01X573300D02*
X582700D01*
X35851Y28624D03*
X48411Y920770D03*
X693601Y10159D03*
X751130Y826309D03*
X765026Y19107D03*
G54D22*
X155300Y26300D03*
G54D23*
X167913Y40748D03*
X219095D03*
G54D14*
X74500Y11400D03*
X88400Y11800D03*
X115000Y10400D03*
X127800D03*
X253011Y12770D03*
X268522Y12786D03*
X418100Y13800D03*
X432200D03*
X558300Y13000D03*
X544800D03*
X651700Y12500D03*
X636600Y12300D03*
G54D24*
X175787Y34842D03*
X179724D03*
X183661D03*
X175787Y58858D03*
X179724D03*
X183661D03*
X187598Y34842D03*
X191535D03*
X195473D03*
X199410D03*
X203347D03*
X207284D03*
X211221D03*
X187598Y58858D03*
X191535D03*
X195473D03*
X199410D03*
X203347D03*
X207284D03*
X211221D03*
G54D15*
X77900Y11400D03*
X118400Y10400D03*
X91800Y11800D03*
X131200Y10400D03*
X256411Y12770D03*
X271922Y12786D03*
X421500Y13800D03*
X435600D03*
X561700Y13000D03*
X548200D03*
X655100Y12500D03*
X640000Y12300D03*
G54D25*
G01X-23515Y-108314D02*
X-55515D01*
G01X-23515Y-124314D02*
Y-204314D01*
G01D02*
X1177585D01*
G01X-27515Y-108314D02*
G02I-12000J0D01*
G01X-39515Y-124314D02*
Y-92314D01*
G01X-23515Y-124314D02*
X1177585D01*
G01X-23515Y-159814D02*
X1177585D01*
G01X-32665Y-108314D02*
G02I-6850J0D01*
G01X74450Y11400D02*
X71200D01*
X71000Y11600D01*
G01X69825Y17550D02*
Y12575D01*
X70800Y11600D01*
X71000D01*
G01X88350Y11800D02*
X84800D01*
X84600Y12000D01*
G01D02*
X83925Y12675D01*
Y17550D01*
G01X114950Y10400D02*
X111100D01*
G01D02*
X108125Y13375D01*
Y16150D01*
G01X127750Y10400D02*
X126200D01*
X124500Y12100D01*
G01D02*
X122225Y14375D01*
Y16150D01*
G01X252961Y12770D02*
X249939D01*
X249763Y12946D01*
X249762D01*
G01X251232Y18504D02*
X249679Y16951D01*
Y13029D01*
X249762Y12946D01*
G01X268472Y12786D02*
X265349D01*
X265042Y13093D01*
G01D02*
Y18214D01*
X265332Y18504D01*
G01X390085Y-124314D02*
Y-204314D01*
G01X418050Y13800D02*
X414700D01*
G01X415025Y19550D02*
X414700Y19225D01*
Y13800D01*
G01X432150D02*
X428600D01*
G01D02*
Y18925D01*
X429225Y19550D01*
G01X527585Y-124314D02*
Y-204314D01*
G01X642585Y-124314D02*
Y-204314D01*
G01X651650Y12500D02*
X647600D01*
G01D02*
Y18025D01*
X647825Y18250D01*
G01X810085Y-124314D02*
Y-204314D01*
G01X980085Y-124314D02*
Y-204314D01*
G01X1177585Y-124314D02*
Y-204314D01*
G01X1205585Y-108314D02*
G02I-12000J0D01*
G01X1200435D02*
G02I-6850J0D01*
G01X1209585D02*
X1177585D01*
G01X1193585Y-124314D02*
Y-92314D01*
G54D16*
X87800Y25050D03*
X83925Y17550D03*
X73700Y25050D03*
X77575Y17550D03*
X69825D03*
X126100Y23650D03*
X129975Y16150D03*
X122225D03*
X91675Y17550D03*
X112000Y23650D03*
X115875Y16150D03*
X108125D03*
X255107Y26004D03*
X258982Y18504D03*
X251232D03*
X269207Y26004D03*
X273082Y18504D03*
X265332D03*
X422775Y19550D03*
X415025D03*
X418900Y27050D03*
X436975Y19550D03*
X429225D03*
X433100Y27050D03*
X563175Y18750D03*
X555425D03*
X548975D03*
X541225D03*
X559300Y26250D03*
X545100D03*
X651700Y25750D03*
X655575Y18250D03*
X647825D03*
X637500Y25750D03*
X641375Y18250D03*
X633625D03*
G54D26*
G01X64300Y19900D02*
X59871D01*
G01X245753Y21417D02*
X241363D01*
X241359Y21413D01*
G01X278574Y20870D02*
X283197D01*
G01X409400Y20700D02*
X405000D01*
G01X442500D02*
X447000D01*
G01X535700Y20300D02*
X531500D01*
G01X568800Y20200D02*
X573000D01*
X573300Y20500D01*
G01X661100Y19700D02*
X665500D01*
G01X628000Y19600D02*
X623300D01*
G54D17*
X64300Y20100D03*
X135500Y19200D03*
X97200Y20600D03*
X102600D03*
X278574Y21070D03*
X245753Y21617D03*
X409400Y20900D03*
X442500D03*
X535700Y20500D03*
X568800Y20400D03*
X628000Y19800D03*
X661100Y19900D03*
G54D27*
G01X544750Y13000D02*
X542125D01*
X541225Y13900D01*
G01D02*
Y18750D01*
G01X558250Y13000D02*
X554500D01*
G01D02*
X554600Y13100D01*
Y17925D01*
X555425Y18750D01*
G54D18*
X82000Y9000D03*
X59000Y47800D03*
X58494Y40465D03*
X47800Y51500D03*
X51573Y47700D03*
X96000Y10500D03*
X135300Y9500D03*
X122800Y8800D03*
X228100Y11100D03*
X260600Y13000D03*
X270500Y8900D03*
X306174Y44235D03*
X300613Y46440D03*
X296425Y49468D03*
X300349Y41423D03*
X420600Y9700D03*
X395500Y20500D03*
X420907Y46740D03*
X424263Y37986D03*
X435200Y9600D03*
X431545Y47333D03*
X428151Y42300D03*
X559800Y8900D03*
X547300Y9000D03*
X523900Y20300D03*
X555698Y37934D03*
X552364Y42400D03*
X545084Y41472D03*
X548424Y47100D03*
X582700Y20500D03*
X653620Y8412D03*
X637981Y8316D03*
X676453Y38712D03*
X676576Y44600D03*
X668361Y43924D03*
X672636Y48100D03*
G54D28*
G01X187598Y34842D02*
Y21710D01*
X169188Y3300D01*
X95520D01*
X90420Y8400D01*
X82600D01*
X82000Y9000D01*
G01X77575Y17550D02*
Y11775D01*
X77950Y11400D01*
G01X82000Y9000D02*
X81500Y9500D01*
X79850D01*
X77950Y11400D01*
G01X59100Y56200D02*
X59000Y56100D01*
Y47800D01*
G01X97200Y26400D02*
X93077Y30523D01*
X71444D01*
X59000Y42967D01*
Y47800D01*
G01X55513Y51513D02*
Y43446D01*
X58494Y40465D01*
G01X87800Y25050D02*
X79350D01*
X75900Y28500D01*
X70459D01*
X58494Y40465D01*
G01X47800Y51500D02*
Y56500D01*
G01X64300Y25900D02*
Y27700D01*
X47800Y44200D01*
Y51500D01*
G01X51573Y47700D02*
Y51573D01*
G01X73700Y25050D02*
X70398D01*
X51573Y43875D01*
Y47700D01*
G01X91675Y17550D02*
Y11975D01*
X91850Y11800D01*
G01X183661Y34842D02*
Y21461D01*
X167500Y5300D01*
X101200D01*
X96000Y10500D01*
G01D02*
X93150D01*
X91850Y11800D01*
G01X135300Y9500D02*
X163600D01*
X175787Y21687D01*
Y34842D01*
G01X129975Y16150D02*
Y12065D01*
X130500Y11540D01*
Y11150D01*
X131250Y10400D01*
G01D02*
X132150Y9500D01*
X135300D01*
G01X118450Y10400D02*
Y13575D01*
X115875Y16150D01*
G01X179724Y34842D02*
Y21624D01*
X165500Y7400D01*
X124200D01*
X122800Y8800D01*
G01X118450Y10400D02*
X121200D01*
X122800Y8800D01*
G01X126100Y23650D02*
Y28200D01*
X126106Y28206D01*
Y29996D01*
G01X112000Y23650D02*
Y27976D01*
X112024Y28000D01*
Y30080D01*
G01X135500Y25000D02*
Y29976D01*
G01X102600Y26400D02*
Y30213D01*
X102586Y30227D01*
G01X256461Y12770D02*
Y10009D01*
X255697Y9245D01*
X229955D01*
X228100Y11100D01*
G01D02*
X226503D01*
X214644Y22959D01*
Y60999D01*
X212365Y63278D01*
X207927D01*
X207284Y62635D01*
Y58858D01*
G01X211221D02*
X213232Y56847D01*
Y19722D01*
X225109Y7845D01*
X269445D01*
X270500Y8900D01*
G01X207284Y34842D02*
Y18276D01*
X220628Y4932D01*
X430532D01*
X435200Y9600D01*
G01X211221Y34842D02*
Y18391D01*
X223280Y6332D01*
X417232D01*
X420600Y9700D01*
G01X199410Y34842D02*
Y18790D01*
X216068Y2132D01*
X553032D01*
X559800Y8900D01*
G01X203347Y34842D02*
Y21953D01*
X203340Y21946D01*
Y19068D01*
X218876Y3532D01*
X541832D01*
X547300Y9000D01*
G01X191535Y34842D02*
Y19165D01*
X211368Y-668D01*
X554371D01*
X558198Y3159D01*
X648367D01*
X653620Y8412D01*
G01X637981Y8316D02*
X634247Y4582D01*
X557469D01*
X553619Y732D01*
X213068D01*
X195473Y18327D01*
Y34842D01*
G01X260600Y13000D02*
X260900Y13300D01*
Y16586D01*
X258982Y18504D01*
G01X256461Y12770D02*
X260370D01*
X260600Y13000D01*
G01X273082Y18504D02*
Y13896D01*
X271972Y12786D01*
G01X270500Y8900D02*
X271972Y10372D01*
Y12786D01*
G01X278574Y26870D02*
X282829D01*
X295079Y39120D01*
X300975D01*
X306090Y44235D01*
X306174D01*
G01X255107Y26004D02*
Y28391D01*
X257572Y30856D01*
X282855D01*
X295740Y43741D01*
X297914D01*
X300613Y46440D01*
G01X245753Y27417D02*
X249253D01*
X254101Y32265D01*
X282284D01*
X296425Y46406D01*
Y49468D01*
G01X269207Y26004D02*
Y26729D01*
X271934Y29456D01*
X283435D01*
X295402Y41423D01*
X300349D01*
G01X307599Y54564D02*
Y45660D01*
X306174Y44235D01*
G01X302200Y51718D02*
Y51708D01*
X300613Y50121D01*
Y46440D01*
G01X296005Y55029D02*
X296425Y54609D01*
Y49468D01*
G01X304088Y48291D02*
Y45162D01*
X300349Y41423D01*
G01X422775Y19550D02*
Y15025D01*
X421550Y13800D01*
G01D02*
Y10650D01*
X420600Y9700D01*
G01X420635Y54538D02*
X420907Y54266D01*
Y46740D01*
G01X409400Y26700D02*
Y28300D01*
X420907Y39807D01*
Y46740D01*
G01X418900Y27050D02*
Y30400D01*
X424263Y35763D01*
Y37986D01*
G01X436975Y19550D02*
Y15125D01*
X435650Y13800D01*
G01D02*
Y10050D01*
X435200Y9600D01*
G01X442500Y26700D02*
X431545Y37655D01*
Y47333D01*
G01X431894Y54627D02*
X431545Y54278D01*
Y47333D01*
G01X433100Y27050D02*
Y31451D01*
X428151Y36400D01*
Y42300D01*
G01D02*
Y52151D01*
G01X424211Y52000D02*
X424263Y51948D01*
Y37986D01*
G01X563175Y18750D02*
Y14425D01*
X561750Y13000D01*
G01D02*
Y10850D01*
X559800Y8900D01*
G01X548975Y18750D02*
Y13725D01*
X548250Y13000D01*
G01D02*
Y9950D01*
X547300Y9000D01*
G01X555996Y54409D02*
X555698Y54111D01*
Y37934D01*
G01X568800Y26200D02*
X566500D01*
X555698Y37002D01*
Y37934D01*
G01X559300Y26250D02*
Y30000D01*
X552364Y36936D01*
Y42400D01*
G01D02*
Y52136D01*
G01X535700Y26300D02*
Y29000D01*
X545084Y38384D01*
Y41472D01*
G01X544789Y54552D02*
X545084Y54257D01*
Y41472D01*
G01X548424Y52000D02*
Y47100D01*
G01X545100Y26250D02*
Y31200D01*
X548424Y34524D01*
Y47100D01*
G01X655150Y12500D02*
Y14875D01*
X655575Y15300D01*
Y18250D01*
G01X653620Y8412D02*
X655150Y9942D01*
Y12500D01*
G01X641375Y18250D02*
Y15375D01*
X640050Y14050D01*
Y12300D01*
G01D02*
Y10385D01*
X637981Y8316D01*
G01X661100Y25700D02*
X663441D01*
X676453Y38712D01*
G01X651700Y25750D02*
Y28700D01*
X652800Y29800D01*
X663580D01*
X676576Y42796D01*
Y44600D01*
G01X628000Y25600D02*
Y28500D01*
X632219Y32719D01*
X661016D01*
X668361Y40064D01*
Y43924D01*
G01X637500Y25750D02*
Y27700D01*
X641071Y31271D01*
X662338D01*
X672636Y41569D01*
Y48100D01*
G01X680189Y54619D02*
X680000Y54430D01*
Y42259D01*
X676453Y38712D01*
G01X676576Y52380D02*
Y44600D01*
G01X668373Y54326D02*
X668361Y54314D01*
Y43924D01*
G01X672636Y48100D02*
Y52380D01*
G54D19*
X64300Y25700D03*
X135500Y24800D03*
X97200Y26200D03*
X102600D03*
X278574Y26670D03*
X245753Y27217D03*
X409400Y26500D03*
X442500D03*
X535700Y26100D03*
X568800Y26000D03*
X628000Y25400D03*
X661100Y25500D03*
G54D29*
G01X981Y-184981D02*
X1855Y-184106D01*
X2510Y-182648D01*
X2947Y-180605D01*
X2510Y-178856D01*
X1637Y-177689D01*
X108Y-176814D01*
X-5787D01*
Y-194314D01*
X1418D01*
X2947Y-193148D01*
X3820Y-191397D01*
X4257Y-189356D01*
X3820Y-187314D01*
X2510Y-185564D01*
X981Y-184981D01*
X-5787D01*
G01X13678Y-194314D02*
Y-182648D01*
G01Y-184981D02*
X14770Y-183814D01*
X15862Y-182939D01*
X17390Y-182648D01*
X18481Y-182939D01*
X19792Y-183814D01*
G01X29650Y-199564D02*
X30960Y-200147D01*
X32707Y-199564D01*
X33798Y-198398D01*
X34672Y-196939D01*
X35981Y-192273D01*
X38820Y-182648D01*
G01X31833D02*
X35981Y-192273D01*
G01X55228Y-184106D02*
X53700Y-182939D01*
X52390Y-182648D01*
X50643Y-183231D01*
X49333Y-184397D01*
X48460Y-186439D01*
X48241Y-188481D01*
X48460Y-190523D01*
X49333Y-192273D01*
X50643Y-193731D01*
X52390Y-194314D01*
X53918Y-193731D01*
X55228Y-192564D01*
G01X65960Y-186439D02*
X72947D01*
X72292Y-184397D01*
X71200Y-183231D01*
X69672Y-182648D01*
X68143Y-182939D01*
X66833Y-183814D01*
X65960Y-185856D01*
X65523Y-187606D01*
Y-189356D01*
X65960Y-191106D01*
X67052Y-192856D01*
X68362Y-194022D01*
X69890Y-194314D01*
X71418Y-193731D01*
X72947Y-191981D01*
G01X109038Y-178273D02*
X107728Y-177397D01*
X106200Y-176814D01*
X104453D01*
X102488Y-177689D01*
X100960Y-179147D01*
X99868Y-180898D01*
X98995Y-183814D01*
X98776Y-186439D01*
X99213Y-189064D01*
X99868Y-190814D01*
X101178Y-192564D01*
X102707Y-193731D01*
X104235Y-194314D01*
X105763D01*
X107292Y-193731D01*
X108602Y-192856D01*
X109694Y-191690D01*
G01X125665Y-194314D02*
Y-182648D01*
G01Y-184689D02*
X124792Y-183523D01*
X123481Y-182939D01*
X121953Y-182648D01*
X120425Y-183231D01*
X119115Y-184397D01*
X118241Y-186147D01*
X117805Y-188481D01*
X118241Y-190814D01*
X119115Y-192564D01*
X120425Y-193731D01*
X121953Y-194314D01*
X123481Y-194022D01*
X124792Y-193148D01*
X125665Y-191981D01*
G01X135523Y-194314D02*
Y-182648D01*
G01Y-185564D02*
X136397Y-184106D01*
X137707Y-182939D01*
X139453Y-182648D01*
X140981Y-182939D01*
X142292Y-184106D01*
X142947Y-186147D01*
Y-194314D01*
G01X152150Y-199564D02*
X153460Y-200147D01*
X155207Y-199564D01*
X156298Y-198398D01*
X157172Y-196939D01*
X158481Y-192273D01*
X161320Y-182648D01*
G01X154333D02*
X158481Y-192273D01*
G01X174235Y-194314D02*
X172925Y-194022D01*
X171615Y-192856D01*
X170741Y-190814D01*
X170305Y-188481D01*
X170741Y-186147D01*
X171615Y-184106D01*
X172925Y-182939D01*
X174235Y-182648D01*
X175545Y-182939D01*
X176855Y-184106D01*
X177728Y-186147D01*
X177947Y-188481D01*
X177728Y-190814D01*
X176855Y-192856D01*
X175545Y-194022D01*
X174235Y-194314D01*
G01X188023D02*
Y-182648D01*
G01Y-185564D02*
X188897Y-184106D01*
X190207Y-182939D01*
X191953Y-182648D01*
X193481Y-182939D01*
X194792Y-184106D01*
X195447Y-186147D01*
Y-194314D01*
G01X222368Y-176814D02*
Y-194314D01*
X231102D01*
G01X248602D02*
X239868D01*
Y-176814D01*
X248602D01*
G01X245108Y-185272D02*
X239868D01*
G01X256932Y-194314D02*
Y-176814D01*
X261298D01*
X263045Y-177689D01*
X264355Y-178856D01*
X265447Y-180605D01*
X266320Y-182648D01*
X266538Y-185564D01*
X266320Y-188481D01*
X265447Y-190523D01*
X264355Y-192273D01*
X263045Y-193439D01*
X261298Y-194314D01*
X256932D01*
G01X298481Y-184981D02*
X299355Y-184106D01*
X300010Y-182648D01*
X300447Y-180605D01*
X300010Y-178856D01*
X299137Y-177689D01*
X297608Y-176814D01*
X291713D01*
Y-194314D01*
X298918D01*
X300447Y-193148D01*
X301320Y-191397D01*
X301757Y-189356D01*
X301320Y-187314D01*
X300010Y-185564D01*
X298481Y-184981D01*
X291713D01*
G01X314235Y-194314D02*
X312925Y-194022D01*
X311615Y-192856D01*
X310741Y-190814D01*
X310305Y-188481D01*
X310741Y-186147D01*
X311615Y-184106D01*
X312925Y-182939D01*
X314235Y-182648D01*
X315545Y-182939D01*
X316855Y-184106D01*
X317728Y-186147D01*
X317947Y-188481D01*
X317728Y-190814D01*
X316855Y-192856D01*
X315545Y-194022D01*
X314235Y-194314D01*
G01X335665D02*
Y-182648D01*
G01Y-184689D02*
X334792Y-183523D01*
X333481Y-182939D01*
X331953Y-182648D01*
X330425Y-183231D01*
X329115Y-184397D01*
X328241Y-186147D01*
X327805Y-188481D01*
X328241Y-190814D01*
X329115Y-192564D01*
X330425Y-193731D01*
X331953Y-194314D01*
X333481Y-194022D01*
X334792Y-193148D01*
X335665Y-191981D01*
G01X346178Y-194314D02*
Y-182648D01*
G01Y-184981D02*
X347270Y-183814D01*
X348362Y-182939D01*
X349890Y-182648D01*
X350981Y-182939D01*
X352292Y-183814D01*
G01X370665Y-176814D02*
Y-194314D01*
G01Y-191690D02*
X369792Y-193148D01*
X368481Y-194022D01*
X366953Y-194314D01*
X365207Y-193731D01*
X363897Y-192273D01*
X363023Y-190523D01*
X362805Y-188481D01*
X363023Y-186439D01*
X363897Y-184689D01*
X365207Y-183231D01*
X366953Y-182648D01*
X368481Y-182939D01*
X369573Y-183523D01*
X370665Y-184689D01*
G01X142308Y-149314D02*
Y-131814D01*
X147985Y-146397D01*
X153662Y-131814D01*
Y-149314D01*
G01X165485D02*
X164175Y-149022D01*
X162865Y-147856D01*
X161991Y-145814D01*
X161555Y-143481D01*
X161991Y-141147D01*
X162865Y-139106D01*
X164175Y-137939D01*
X165485Y-137648D01*
X166795Y-137939D01*
X168105Y-139106D01*
X168978Y-141147D01*
X169197Y-143481D01*
X168978Y-145814D01*
X168105Y-147856D01*
X166795Y-149022D01*
X165485Y-149314D01*
G01X186915Y-131814D02*
Y-149314D01*
G01Y-146690D02*
X186042Y-148148D01*
X184731Y-149022D01*
X183203Y-149314D01*
X181457Y-148731D01*
X180147Y-147273D01*
X179273Y-145523D01*
X179055Y-143481D01*
X179273Y-141439D01*
X180147Y-139689D01*
X181457Y-138231D01*
X183203Y-137648D01*
X184731Y-137939D01*
X185823Y-138523D01*
X186915Y-139689D01*
G01X197210Y-141439D02*
X204197D01*
X203542Y-139397D01*
X202450Y-138231D01*
X200922Y-137648D01*
X199393Y-137939D01*
X198083Y-138814D01*
X197210Y-140856D01*
X196773Y-142606D01*
Y-144356D01*
X197210Y-146106D01*
X198302Y-147856D01*
X199612Y-149022D01*
X201140Y-149314D01*
X202668Y-148731D01*
X204197Y-146981D01*
G01X217985Y-149314D02*
Y-131814D01*
G01X423785Y-194314D02*
Y-176814D01*
X421165Y-180314D01*
G01Y-194314D02*
X426405D01*
G01X437137Y-187023D02*
X438665Y-184981D01*
X439975Y-183814D01*
X441722Y-183231D01*
X443250Y-183814D01*
X444342Y-184981D01*
X445215Y-186731D01*
X445433Y-188772D01*
X445215Y-190523D01*
X444342Y-192273D01*
X443031Y-193731D01*
X441503Y-194314D01*
X439757Y-193731D01*
X438228Y-191981D01*
X437355Y-189356D01*
X437137Y-186439D01*
X437573Y-182648D01*
X438228Y-180605D01*
X439320Y-178564D01*
X440848Y-177106D01*
X442377Y-176814D01*
X443905Y-177397D01*
X444997Y-178856D01*
G01X453982Y-190814D02*
X455291Y-192856D01*
X457038Y-194022D01*
X459003Y-194314D01*
X460750Y-194022D01*
X462497Y-192564D01*
X463588Y-190814D01*
X463807Y-189064D01*
X463370Y-187023D01*
X461842Y-185564D01*
X460313Y-184981D01*
X458348D01*
G01X460313D02*
X461623Y-184106D01*
X462715Y-182648D01*
X463152Y-180898D01*
X462715Y-179147D01*
X461623Y-177689D01*
X459658Y-176814D01*
X457693Y-177106D01*
X455728Y-178273D01*
G01X478905Y-194314D02*
Y-176814D01*
X470826Y-189356D01*
X481744D01*
G01X493348Y-194314D02*
X493785Y-190523D01*
X494440Y-187314D01*
X495313Y-184397D01*
X496405Y-181189D01*
X498152Y-176814D01*
X489418D01*
G01X410668Y-149314D02*
Y-131814D01*
X415908D01*
X417655Y-132689D01*
X418965Y-134731D01*
X419402Y-137064D01*
X418965Y-139397D01*
X417873Y-141147D01*
X415908Y-142023D01*
X410668D01*
G01X437338Y-133273D02*
X436028Y-132397D01*
X434500Y-131814D01*
X432753D01*
X430788Y-132689D01*
X429260Y-134147D01*
X428168Y-135898D01*
X427295Y-138814D01*
X427076Y-141439D01*
X427513Y-144064D01*
X428168Y-145814D01*
X429478Y-147564D01*
X431007Y-148731D01*
X432535Y-149314D01*
X434063D01*
X435592Y-148731D01*
X436902Y-147856D01*
X437994Y-146690D01*
G01X451781Y-139981D02*
X452655Y-139106D01*
X453310Y-137648D01*
X453747Y-135605D01*
X453310Y-133856D01*
X452437Y-132689D01*
X450908Y-131814D01*
X445013D01*
Y-149314D01*
X452218D01*
X453747Y-148148D01*
X454620Y-146397D01*
X455057Y-144356D01*
X454620Y-142314D01*
X453310Y-140564D01*
X451781Y-139981D01*
X445013D01*
G01X460985Y-155147D02*
X474085D01*
G01X480013Y-149314D02*
Y-131814D01*
X490057Y-149314D01*
Y-131814D01*
G01X502535Y-149314D02*
X500788Y-149022D01*
X499260Y-147856D01*
X497950Y-146106D01*
X497076Y-144064D01*
X496640Y-141731D01*
Y-139397D01*
X497076Y-137064D01*
X497950Y-135022D01*
X499260Y-133273D01*
X500788Y-132106D01*
X502535Y-131814D01*
X504281Y-132106D01*
X505810Y-133273D01*
X507120Y-135022D01*
X507994Y-137064D01*
X508430Y-139397D01*
Y-141731D01*
X507994Y-144064D01*
X507120Y-146106D01*
X505810Y-147856D01*
X504281Y-149022D01*
X502535Y-149314D01*
G01X553376Y-131814D02*
X558835Y-149314D01*
X564294Y-131814D01*
G01X580702Y-149314D02*
X571968D01*
Y-131814D01*
X580702D01*
G01X577208Y-140272D02*
X571968D01*
G01X589468Y-149314D02*
Y-131814D01*
X594927D01*
X596673Y-132689D01*
X597765Y-133856D01*
X598202Y-136189D01*
X597765Y-138523D01*
X596455Y-139981D01*
X594927Y-140856D01*
X589468D01*
G01X594927D02*
X598202Y-149314D01*
G01X611335Y-149897D02*
X610898Y-149606D01*
Y-149022D01*
X611335Y-148731D01*
X611772Y-149022D01*
Y-149606D01*
X611335Y-149897D01*
G01X571750Y-191981D02*
X573497Y-193439D01*
X575462Y-194314D01*
X577208D01*
X578955Y-193439D01*
X580265Y-191981D01*
X580920Y-189939D01*
X580483Y-187898D01*
X579392Y-186147D01*
X577427Y-184981D01*
X574807Y-184397D01*
X573278Y-183231D01*
X572623Y-181189D01*
X573060Y-179147D01*
X574152Y-177689D01*
X575680Y-176814D01*
X577208D01*
X578737Y-177397D01*
X580047Y-178856D01*
G01X598638Y-178273D02*
X597328Y-177397D01*
X595800Y-176814D01*
X594053D01*
X592088Y-177689D01*
X590560Y-179147D01*
X589468Y-180898D01*
X588595Y-183814D01*
X588376Y-186439D01*
X588813Y-189064D01*
X589468Y-190814D01*
X590778Y-192564D01*
X592307Y-193731D01*
X593835Y-194314D01*
X595363D01*
X596892Y-193731D01*
X598202Y-192856D01*
X599294Y-191690D01*
G01X686918Y-131814D02*
Y-149314D01*
X695652D01*
G01X712715D02*
Y-137648D01*
G01Y-139689D02*
X711842Y-138523D01*
X710531Y-137939D01*
X709003Y-137648D01*
X707475Y-138231D01*
X706165Y-139397D01*
X705291Y-141147D01*
X704855Y-143481D01*
X705291Y-145814D01*
X706165Y-147564D01*
X707475Y-148731D01*
X709003Y-149314D01*
X710531Y-149022D01*
X711842Y-148148D01*
X712715Y-146981D01*
G01X721700Y-154564D02*
X723010Y-155147D01*
X724757Y-154564D01*
X725848Y-153398D01*
X726722Y-151939D01*
X728031Y-147273D01*
X730870Y-137648D01*
G01X723883D02*
X728031Y-147273D01*
G01X740510Y-141439D02*
X747497D01*
X746842Y-139397D01*
X745750Y-138231D01*
X744222Y-137648D01*
X742693Y-137939D01*
X741383Y-138814D01*
X740510Y-140856D01*
X740073Y-142606D01*
Y-144356D01*
X740510Y-146106D01*
X741602Y-147856D01*
X742912Y-149022D01*
X744440Y-149314D01*
X745968Y-148731D01*
X747497Y-146981D01*
G01X758228Y-149314D02*
Y-137648D01*
G01Y-139981D02*
X759320Y-138814D01*
X760412Y-137939D01*
X761940Y-137648D01*
X763031Y-137939D01*
X764342Y-138814D01*
G01X739402Y-176814D02*
Y-194314D01*
X730668D01*
G01X721683Y-179731D02*
X720373Y-177981D01*
X718845Y-177106D01*
X717098Y-176814D01*
X714915Y-177397D01*
X713387Y-178856D01*
X712950Y-180605D01*
X713168Y-182356D01*
X714042Y-183814D01*
X718408Y-186731D01*
X720373Y-188772D01*
X721683Y-191690D01*
X722120Y-194314D01*
X712950D01*
G01X851335D02*
X849588Y-194022D01*
X848060Y-192856D01*
X846750Y-191106D01*
X845876Y-189064D01*
X845440Y-186731D01*
Y-184397D01*
X845876Y-182064D01*
X846750Y-180022D01*
X848060Y-178273D01*
X849588Y-177106D01*
X851335Y-176814D01*
X853081Y-177106D01*
X854610Y-178273D01*
X855920Y-180022D01*
X856794Y-182064D01*
X857230Y-184397D01*
Y-186731D01*
X856794Y-189064D01*
X855920Y-191106D01*
X854610Y-192856D01*
X853081Y-194022D01*
X851335Y-194314D01*
G01X853081Y-189647D02*
X855702Y-194314D01*
G01X864032Y-176814D02*
Y-189356D01*
X864905Y-191981D01*
X866652Y-193731D01*
X868835Y-194314D01*
X871018Y-193731D01*
X872765Y-191981D01*
X873638Y-189356D01*
Y-176814D01*
G01X883715D02*
X888955D01*
G01X886335D02*
Y-194314D01*
G01X883715D02*
X888955D01*
G01X898813D02*
Y-176814D01*
X908857Y-194314D01*
Y-176814D01*
G01X926138Y-178273D02*
X924828Y-177397D01*
X923300Y-176814D01*
X921553D01*
X919588Y-177689D01*
X918060Y-179147D01*
X916968Y-180898D01*
X916095Y-183814D01*
X915876Y-186439D01*
X916313Y-189064D01*
X916968Y-190814D01*
X918278Y-192564D01*
X919807Y-193731D01*
X921335Y-194314D01*
X922863D01*
X924392Y-193731D01*
X925702Y-192856D01*
X926794Y-191690D01*
G01X938835Y-194314D02*
Y-186439D01*
X934468Y-176814D01*
G01X943202D02*
X938835Y-186439D01*
G01X829032Y-149314D02*
Y-131814D01*
X833398D01*
X835145Y-132689D01*
X836455Y-133856D01*
X837547Y-135605D01*
X838420Y-137648D01*
X838638Y-140564D01*
X838420Y-143481D01*
X837547Y-145523D01*
X836455Y-147273D01*
X835145Y-148439D01*
X833398Y-149314D01*
X829032D01*
G01X848060Y-141439D02*
X855047D01*
X854392Y-139397D01*
X853300Y-138231D01*
X851772Y-137648D01*
X850243Y-137939D01*
X848933Y-138814D01*
X848060Y-140856D01*
X847623Y-142606D01*
Y-144356D01*
X848060Y-146106D01*
X849152Y-147856D01*
X850462Y-149022D01*
X851990Y-149314D01*
X853518Y-148731D01*
X855047Y-146981D01*
G01X865560Y-147273D02*
X866652Y-148439D01*
X868180Y-149314D01*
X869490D01*
X870800Y-148731D01*
X871673Y-147856D01*
X872110Y-146690D01*
X871892Y-144939D01*
X871018Y-144064D01*
X867088Y-142314D01*
X866215Y-140272D01*
X866652Y-138814D01*
X867525Y-137939D01*
X868835Y-137648D01*
X870145Y-137939D01*
X871455Y-138814D01*
G01X886335Y-137648D02*
Y-149314D01*
G01Y-132981D02*
X885898Y-132689D01*
Y-132106D01*
X886335Y-131814D01*
X886772Y-132106D01*
Y-132689D01*
X886335Y-132981D01*
G01X900778Y-153689D02*
X902307Y-154856D01*
X904053Y-155147D01*
X905581Y-154856D01*
X906892Y-153398D01*
X907765Y-151356D01*
Y-137648D01*
G01Y-139981D02*
X906892Y-138814D01*
X905581Y-137939D01*
X904053Y-137648D01*
X902307Y-138231D01*
X901215Y-139397D01*
X900341Y-141439D01*
X899905Y-143481D01*
X900123Y-145231D01*
X900997Y-147273D01*
X902307Y-148731D01*
X904053Y-149314D01*
X905363Y-149022D01*
X906892Y-147856D01*
X907765Y-146690D01*
G01X917623Y-149314D02*
Y-137648D01*
G01Y-140564D02*
X918497Y-139106D01*
X919807Y-137939D01*
X921553Y-137648D01*
X923081Y-137939D01*
X924392Y-139106D01*
X925047Y-141147D01*
Y-149314D01*
G01X935560Y-141439D02*
X942547D01*
X941892Y-139397D01*
X940800Y-138231D01*
X939272Y-137648D01*
X937743Y-137939D01*
X936433Y-138814D01*
X935560Y-140856D01*
X935123Y-142606D01*
Y-144356D01*
X935560Y-146106D01*
X936652Y-147856D01*
X937962Y-149022D01*
X939490Y-149314D01*
X941018Y-148731D01*
X942547Y-146981D01*
G01X953278Y-149314D02*
Y-137648D01*
G01Y-139981D02*
X954370Y-138814D01*
X955462Y-137939D01*
X956990Y-137648D01*
X958081Y-137939D01*
X959392Y-138814D01*
G01X1000035Y-176814D02*
X998288Y-177397D01*
X996978Y-178856D01*
X996105Y-180605D01*
X995450Y-182939D01*
X995232Y-185564D01*
X995450Y-188189D01*
X996105Y-190523D01*
X996978Y-192273D01*
X998288Y-193731D01*
X1000035Y-194314D01*
X1001781Y-193731D01*
X1003092Y-192273D01*
X1003965Y-190523D01*
X1004620Y-188189D01*
X1004838Y-185564D01*
X1004620Y-182939D01*
X1003965Y-180605D01*
X1003092Y-178856D01*
X1001781Y-177397D01*
X1000035Y-176814D01*
G01X1012732Y-190814D02*
X1014041Y-192856D01*
X1015788Y-194022D01*
X1017753Y-194314D01*
X1019500Y-194022D01*
X1021247Y-192564D01*
X1022338Y-190814D01*
X1022557Y-189064D01*
X1022120Y-187023D01*
X1020592Y-185564D01*
X1019063Y-184981D01*
X1017098D01*
G01X1019063D02*
X1020373Y-184106D01*
X1021465Y-182648D01*
X1021902Y-180898D01*
X1021465Y-179147D01*
X1020373Y-177689D01*
X1018408Y-176814D01*
X1016443Y-177106D01*
X1014478Y-178273D01*
G01X1031105Y-194897D02*
X1038965Y-176814D01*
G01X1052535Y-194314D02*
Y-176814D01*
X1049915Y-180314D01*
G01Y-194314D02*
X1055155D01*
G01X1065232Y-190814D02*
X1066541Y-192856D01*
X1068288Y-194022D01*
X1070253Y-194314D01*
X1072000Y-194022D01*
X1073747Y-192564D01*
X1074838Y-190814D01*
X1075057Y-189064D01*
X1074620Y-187023D01*
X1073092Y-185564D01*
X1071563Y-184981D01*
X1069598D01*
G01X1071563D02*
X1072873Y-184106D01*
X1073965Y-182648D01*
X1074402Y-180898D01*
X1073965Y-179147D01*
X1072873Y-177689D01*
X1070908Y-176814D01*
X1068943Y-177106D01*
X1066978Y-178273D01*
G01X1083605Y-194897D02*
X1091465Y-176814D01*
G01X1100887Y-179731D02*
X1102197Y-177981D01*
X1103725Y-177106D01*
X1105472Y-176814D01*
X1107655Y-177397D01*
X1109183Y-178856D01*
X1109620Y-180605D01*
X1109402Y-182356D01*
X1108528Y-183814D01*
X1104162Y-186731D01*
X1102197Y-188772D01*
X1100887Y-191690D01*
X1100450Y-194314D01*
X1109620D01*
G01X1122535Y-176814D02*
X1120788Y-177397D01*
X1119478Y-178856D01*
X1118605Y-180605D01*
X1117950Y-182939D01*
X1117732Y-185564D01*
X1117950Y-188189D01*
X1118605Y-190523D01*
X1119478Y-192273D01*
X1120788Y-193731D01*
X1122535Y-194314D01*
X1124281Y-193731D01*
X1125592Y-192273D01*
X1126465Y-190523D01*
X1127120Y-188189D01*
X1127338Y-185564D01*
X1127120Y-182939D01*
X1126465Y-180605D01*
X1125592Y-178856D01*
X1124281Y-177397D01*
X1122535Y-176814D01*
G01X1140035Y-194314D02*
Y-176814D01*
X1137415Y-180314D01*
G01Y-194314D02*
X1142655D01*
G01X1157098D02*
X1157535Y-190523D01*
X1158190Y-187314D01*
X1159063Y-184397D01*
X1160155Y-181189D01*
X1161902Y-176814D01*
X1153168D01*
G01X1047732Y-149314D02*
Y-131814D01*
X1052098D01*
X1053845Y-132689D01*
X1055155Y-133856D01*
X1056247Y-135605D01*
X1057120Y-137648D01*
X1057338Y-140564D01*
X1057120Y-143481D01*
X1056247Y-145523D01*
X1055155Y-147273D01*
X1053845Y-148439D01*
X1052098Y-149314D01*
X1047732D01*
G01X1073965D02*
Y-137648D01*
G01Y-139689D02*
X1073092Y-138523D01*
X1071781Y-137939D01*
X1070253Y-137648D01*
X1068725Y-138231D01*
X1067415Y-139397D01*
X1066541Y-141147D01*
X1066105Y-143481D01*
X1066541Y-145814D01*
X1067415Y-147564D01*
X1068725Y-148731D01*
X1070253Y-149314D01*
X1071781Y-149022D01*
X1073092Y-148148D01*
X1073965Y-146981D01*
G01X1087535Y-131814D02*
Y-149314D01*
G01X1084478Y-137648D02*
X1090592D01*
G01X1101760Y-141439D02*
X1108747D01*
X1108092Y-139397D01*
X1107000Y-138231D01*
X1105472Y-137648D01*
X1103943Y-137939D01*
X1102633Y-138814D01*
X1101760Y-140856D01*
X1101323Y-142606D01*
Y-144356D01*
X1101760Y-146106D01*
X1102852Y-147856D01*
X1104162Y-149022D01*
X1105690Y-149314D01*
X1107218Y-148731D01*
X1108747Y-146981D01*
M02*
